# SCM (Grand Teton) — schematic netlist excerpt (pin names and nets, part order shuffled) for the footprints in the layout excerpt that follows; sources: Cadence DE-HDL packaged netlist, KiCad conversion of 12092022_DA0F0TMDCD0_F0T_Management_Board_D_brd_V3_OCP.brd

R351  Q_RES  120 1% CHIP  pkg 0402LF  page 20 : A = M_BMC_DDR4_MA<0> ; B = P1V2_AUX
C282  Q_CAP  1UF 25V 10% X6S  pkg C0402  page 17 : A = ADCVREFEXT0 ; B = GND

(kicad_pcb
	(version 20260206)
	(generator "pcbnew")
	(generator_version "10.0")
	(general
		(thickness 1.6)
		(legacy_teardrops no)
	)
	(paper "A4")
	(title_block
		(title "12092022_DA0F0TMDCD0_F0T_Management_Board_D_brd_V3_OCP.brd")
		(comment 1 "Grand Teton / footprints 1002-1003 of 1440")
	)
	(layers
		(0 "F.Cu" signal "TOP")
		(4 "In1.Cu" signal "GND")
		(6 "In2.Cu" signal "IN1")
		(8 "In3.Cu" signal "GND1")
		(10 "In4.Cu" signal "IN2")
		(12 "In5.Cu" signal "VCC")
		(14 "In6.Cu" signal "VCC1")
		(16 "In7.Cu" signal "IN3")
		(18 "In8.Cu" signal "GND2")
		(20 "In9.Cu" signal "IN4")
		(22 "In10.Cu" signal "GND3")
		(2 "B.Cu" signal "BOTTOM")
		(9 "F.Adhes" user "F.Adhesive")
		(11 "B.Adhes" user "B.Adhesive")
		(13 "F.Paste" user "Package Geometry/Pastemask Top")
		(15 "B.Paste" user "Package Geometry/Pastemask Bottom")
		(5 "F.SilkS" user "Ref Des/Silkscreen Top")
		(7 "B.SilkS" user "Ref Des/Silkscreen Bottom")
		(1 "F.Mask" user "Board Geometry/Soldermask Top")
		(3 "B.Mask" user "Board Geometry/Soldermask Bottom")
		(17 "Dwgs.User" user "User.Drawings")
		(19 "Cmts.User" user "User.Comments")
		(21 "Eco1.User" user "User.Eco1")
		(23 "Eco2.User" user "User.Eco2")
		(25 "Edge.Cuts" user "Board Geometry/Outline")
		(27 "Margin" user)
		(31 "F.CrtYd" user "Package Geometry/Place Bound Top")
		(29 "B.CrtYd" user "Package Geometry/Place Bound Bottom")
		(35 "F.Fab" user "Ref Des/Assembly Top")
		(33 "B.Fab" user "Ref Des/Assembly Bottom")
	)
	(footprint ""
		(layer "B.Cu")
		(at 56.861964 -71.064882 180)
		(property "Reference" "C282"
			(at 0 0 0)
			(layer "B.SilkS")
			(hide yes)
			(effects
				(font
					(size 1.27 1.27)
				)
				(justify mirror)
			)
		)
		(property "Value" ""
			(at 0 0 0)
			(layer "B.Fab")
			(effects
				(font
					(size 1.27 1.27)
				)
				(justify mirror)
			)
		)
		(duplicate_pad_numbers_are_jumpers no)
		(fp_line
			(start 0.7874 0.4064)
			(end 0.7874 -0.4064)
			(stroke
				(width 0.1524)
				(type default)
			)
			(layer "B.SilkS")
		)
		(fp_line
			(start 0.7874 -0.4064)
			(end -0.7874 -0.4064)
			(stroke
				(width 0.1524)
				(type default)
			)
			(layer "B.SilkS")
		)
		(fp_line
			(start -0.7874 0.4064)
			(end 0.7874 0.4064)
			(stroke
				(width 0.1524)
				(type default)
			)
			(layer "B.SilkS")
		)
		(fp_line
			(start -0.7874 -0.4064)
			(end -0.7874 0.4064)
			(stroke
				(width 0.1524)
				(type default)
			)
			(layer "B.SilkS")
		)
		(fp_line
			(start 0.67945 0.3048)
			(end 0.67945 -0.305054)
			(stroke
				(width 0.1)
				(type default)
			)
			(layer "B.Fab")
		)
		(fp_line
			(start 0.67945 -0.305054)
			(end 0.12065 -0.305054)
			(stroke
				(width 0.1)
				(type default)
			)
			(layer "B.Fab")
		)
		(fp_line
			(start 0.12065 0.3048)
			(end 0.67945 0.3048)
			(stroke
				(width 0.1)
				(type default)
			)
			(layer "B.Fab")
		)
		(fp_line
			(start 0.12065 0.2794)
			(end 0.12065 0.3048)
			(stroke
				(width 0.1)
				(type default)
			)
			(layer "B.Fab")
		)
		(fp_line
			(start 0.12065 -0.2794)
			(end -0.12065 -0.2794)
			(stroke
				(width 0.1)
				(type default)
			)
			(layer "B.Fab")
		)
		(fp_line
			(start 0.12065 -0.305054)
			(end 0.12065 -0.2794)
			(stroke
				(width 0.1)
				(type default)
			)
			(layer "B.Fab")
		)
		(fp_line
			(start -0.120396 0.3048)
			(end -0.120396 0.2794)
			(stroke
				(width 0.1)
				(type default)
			)
			(layer "B.Fab")
		)
		(fp_line
			(start -0.120396 0.2794)
			(end 0.12065 0.2794)
			(stroke
				(width 0.1)
				(type default)
			)
			(layer "B.Fab")
		)
		(fp_line
			(start -0.12065 -0.2794)
			(end -0.12065 -0.3048)
			(stroke
				(width 0.1)
				(type default)
			)
			(layer "B.Fab")
		)
		(fp_line
			(start -0.12065 -0.3048)
			(end -0.67945 -0.3048)
			(stroke
				(width 0.1)
				(type default)
			)
			(layer "B.Fab")
		)
		(fp_line
			(start -0.67945 0.3048)
			(end -0.120396 0.3048)
			(stroke
				(width 0.1)
				(type default)
			)
			(layer "B.Fab")
		)
		(fp_line
			(start -0.67945 -0.3048)
			(end -0.67945 0.3048)
			(stroke
				(width 0.1)
				(type default)
			)
			(layer "B.Fab")
		)
		(pad "1" smd circle
			(at 0.40005 0)
			(size 0 0)
			(layers "B.Cu" "B.Mask" "B.Paste")
			(net "ADCVREFEXT0")
		)
		(pad "2" smd circle
			(at -0.40005 0)
			(size 0 0)
			(layers "B.Cu" "B.Mask" "B.Paste")
			(net "GND")
		)
	)
	(footprint ""
		(layer "B.Cu")
		(at 80.755744 -37.559488 90)
		(property "Reference" "R351"
			(at 0 0 90)
			(layer "B.SilkS")
			(hide yes)
			(effects
				(font
					(size 1.27 1.27)
				)
				(justify mirror)
			)
		)
		(property "Value" ""
			(at 0 0 90)
			(layer "B.Fab")
			(effects
				(font
					(size 1.27 1.27)
				)
				(justify mirror)
			)
		)
		(duplicate_pad_numbers_are_jumpers no)
		(fp_line
			(start 0.7874 -0.4064)
			(end -0.7874 -0.4064)
			(stroke
				(width 0.1524)
				(type default)
			)
			(layer "B.SilkS")
		)
		(fp_line
			(start -0.7874 -0.4064)
			(end -0.7874 0.4064)
			(stroke
				(width 0.1524)
				(type default)
			)
			(layer "B.SilkS")
		)
		(fp_line
			(start 0.7874 0.4064)
			(end 0.7874 -0.4064)
			(stroke
				(width 0.1524)
				(type default)
			)
			(layer "B.SilkS")
		)
		(fp_line
			(start -0.7874 0.4064)
			(end 0.7874 0.4064)
			(stroke
				(width 0.1524)
				(type default)
			)
			(layer "B.SilkS")
		)
		(fp_line
			(start 0.67945 -0.305054)
			(end 0.12065 -0.305054)
			(stroke
				(width 0.1)
				(type default)
			)
			(layer "B.Fab")
		)
		(fp_line
			(start 0.12065 -0.305054)
			(end 0.12065 -0.2794)
			(stroke
				(width 0.1)
				(type default)
			)
			(layer "B.Fab")
		)
		(fp_line
			(start -0.12065 -0.3048)
			(end -0.67945 -0.3048)
			(stroke
				(width 0.1)
				(type default)
			)
			(layer "B.Fab")
		)
		(fp_line
			(start -0.67945 -0.3048)
			(end -0.67945 0.3048)
			(stroke
				(width 0.1)
				(type default)
			)
			(layer "B.Fab")
		)
		(fp_line
			(start 0.12065 -0.2794)
			(end -0.12065 -0.2794)
			(stroke
				(width 0.1)
				(type default)
			)
			(layer "B.Fab")
		)
		(fp_line
			(start -0.12065 -0.2794)
			(end -0.12065 -0.3048)
			(stroke
				(width 0.1)
				(type default)
			)
			(layer "B.Fab")
		)
		(fp_line
			(start 0.12065 0.2794)
			(end 0.12065 0.3048)
			(stroke
				(width 0.1)
				(type default)
			)
			(layer "B.Fab")
		)
		(fp_line
			(start -0.120396 0.2794)
			(end 0.12065 0.2794)
			(stroke
				(width 0.1)
				(type default)
			)
			(layer "B.Fab")
		)
		(fp_line
			(start 0.67945 0.3048)
			(end 0.67945 -0.305054)
			(stroke
				(width 0.1)
				(type default)
			)
			(layer "B.Fab")
		)
		(fp_line
			(start 0.12065 0.3048)
			(end 0.67945 0.3048)
			(stroke
				(width 0.1)
				(type default)
			)
			(layer "B.Fab")
		)
		(fp_line
			(start -0.120396 0.3048)
			(end -0.120396 0.2794)
			(stroke
				(width 0.1)
				(type default)
			)
			(layer "B.Fab")
		)
		(fp_line
			(start -0.67945 0.3048)
			(end -0.120396 0.3048)
			(stroke
				(width 0.1)
				(type default)
			)
			(layer "B.Fab")
		)
		(pad "1" smd circle
			(at 0.40005 0 270)
			(size 0 0)
			(layers "B.Cu" "B.Mask" "B.Paste")
			(net "M_BMC_DDR4_MA<0>")
		)
		(pad "2" smd circle
			(at -0.40005 0 270)
			(size 0 0)
			(layers "B.Cu" "B.Mask" "B.Paste")
			(net "P1V2_AUX")
		)
	)
)
